FILE_TYPE = MULTI_PHYS_TABLE;

PART 'M24M02DRMN6TP'

{========================================================================================}
:VALUE            | PART_TYPE | MATERIAL | PART_NUMBER       = STANDARD    | LIFECYCLE      | PART_NUMBER       | JEDEC_TYPE | DESCRIPTION                             | MANUFTR | MANUF_PN         | RD_CMPLS_LVL | CMPLS_LVL | FROM_PJ      | CLASS | DIP_SMD | DATA                        | EE_CHECK_LIST | FP_ECN               | PSL | CREATOR | STATUS | MSD | ESD_CDM | ESD_HBM | ESD_MM | PIN_LENGTH_SHORT_PIN | PIN_LENGTH_LONG_PIN | CREATEDAY  ;
{========================================================================================}
 'M24M02-DRMN6TP' | 'SMLF'    | 'IC'     | 'AKE33Z00600'(!)  = ''          | ''             | 'AKE33Z00600'     |'SOIC8XH'| 'IC EEPROM(8P)M24M02-DRMN6TP(SO)'       | 'SGT'   | 'M24M02-DRMN6TP' | 'EP(V1)'     | ''        | 'S5S-YVETTE' | 'IC'  | ''      | 'SGT_M24M02-DRMN6TP_v7.pdf' | ''            | 'M24M02-DRMN6TP.pdf' | ''  | ''      | ''     | ''  | ''      | ''      | ''     | ''                   | ''                  | '20161220'
 'M24M02-DRMN6TP' | 'SMLF'    | 'EMPTY'  | 'AKE33Z00600'(!)  = ''          | ''             | 'AKE33Z00600'     |'SOIC8XH'| 'IC EEPROM(8P)M24M02-DRMN6TP(SO)'       | 'SGT'   | 'M24M02-DRMN6TP' | 'EP(V1)'     | ''        | 'S5S-YVETTE' | 'IC'  | ''      | 'SGT_M24M02-DRMN6TP_v7.pdf' | ''            | 'M24M02-DRMN6TP.pdf' | ''  | ''      | ''     | ''  | ''      | ''      | ''     | ''                   | ''                  | '20161220'
 'M24M02-DRMN6TP' | 'SMLF'    | 'IC'     | 'AKE33Z00600SEL1'(!) = ''               | ''               | 'AKE33Z00600SEL1' |'SOIC8XH'| 'IC EEPROM(8P)M24M02-DRMN6TP(SO)SELASN' | 'SGT'   | 'M24M02-DRMN6TP' | 'EP(V1)'     | ''        | 'S5S-YVETTE' | 'IC'  | ''      | 'SGT_M24M02-DRMN6TP_v7.pdf' | ''            | 'SEL_15QPN.xlsx'     | ''  | ''      | ''     | ''  | ''      | ''      | ''     | ''                   | ''                  | '20230627'
 'M24M02-DRMN6TP' | 'SMLF'    | 'EMPTY'  | 'AKE33Z00600SEL1'(!) = ''               | ''               | 'AKE33Z00600SEL1' |'SOIC8XH'| 'IC EEPROM(8P)M24M02-DRMN6TP(SO)SELASN' | 'SGT'   | 'M24M02-DRMN6TP' | 'EP(V1)'     | ''        | 'S5S-YVETTE' | 'IC'  | ''      | 'SGT_M24M02-DRMN6TP_v7.pdf' | ''            | 'SEL_15QPN.xlsx'     | ''  | ''      | ''     | ''  | ''      | ''      | ''     | ''                   | ''                  | '20230627'

END_PART

END.

